#ISCELL
  mstr_misc dns *
  *
#ISCELL
  pure_quanta quanta_title_block_c *
  *
#ISCELL
  pure_quanta_power universal_gnd *
  page198_i1
#CELL
  pure_quanta q_cap *
  page198_i100
#CELL
  pure_quanta q_cap *
  page198_i101
#CELL
  pure_quanta q_cap *
  page198_i102
#ISCELL
  pure_quanta_power universal_gnd *
  page198_i103
#ISCELL
  pure_quanta_power universal_gnd *
  page198_i104
#CELL
  pure_quanta q_res *
  page198_i105
#CELL
  pure_quanta q_cap *
  page198_i106
#CELL
  pure_quanta q_cap *
  page198_i108
#ISCELL
  pure_quanta_power universal_gnd *
  page198_i109
#ISCELL
  pure_quanta_power universal_gnd *
  page198_i110
#CELL
  pure_quanta q_res *
  page198_i111
#CELL
  pure_quanta q_cap *
  page198_i112
#ISCELL
  pure_quanta_power universal_gnd *
  page198_i114
#ISCELL
  pure_quanta_power universal_gnd *
  page198_i115
#ISCELL
  pure_quanta_power universal_gnd *
  page198_i117
#CELL
  pure_quanta q_res *
  page198_i118
#CELL
  pure_quanta q_cap *
  page198_i119
#ISCELL
  pure_quanta_power universal_gnd *
  page198_i120
#CELL
  pure_quanta q_res *
  page198_i121
#CELL
  pure_quanta q_cap *
  page198_i122
#ISCELL
  pure_quanta_power vcc_core *
  page198_i123
#ISCELL
  pure_quanta_power vcc_core *
  page198_i124
#ISCELL
  standard offpage *
  page198_i127
#CELL
  pure_quanta q_inductor *
  page198_i128
#ISCELL
  pure_quanta_power universal_gnd *
  page198_i129
#ISCELL
  pure_quanta_power universal_gnd *
  page198_i14
#CELL
  pure_quanta q_res *
  page198_i15
#CELL
  pure_quanta q_res *
  page198_i2
#ISCELL
  standard offpage *
  page198_i21
#ISCELL
  standard offpage *
  page198_i22
#CELL
  pure_quanta isl99390frztr5935 *
  page198_i23
#ISCELL
  pure_quanta_power universal_gnd *
  page198_i24
#CELL
  pure_quanta isl99390frztr5935 *
  page198_i26
#CELL
  pure_quanta q_cap *
  page198_i28
#ISCELL
  pure_quanta_power universal_gnd *
  page198_i29
#ISCELL
  standard offpage *
  page198_i33
#ISCELL
  standard offpage *
  page198_i34
#ISCELL
  standard offpage *
  page198_i4
#CELL
  pure_quanta q_cap *
  page198_i44
#CELL
  pure_quanta q_inductor4p_14 *
  page198_i46
#ISCELL
  pure_quanta_power universal_gnd *
  page198_i49
#ISCELL
  standard offpage *
  page198_i5
#CELL
  pure_quanta q_cap *
  page198_i51
#CELL
  pure_quanta q_cap *
  page198_i52
#CELL
  pure_quanta q_cap *
  page198_i55
#CELL
  pure_quanta q_res *
  page198_i57
#CELL
  pure_quanta q_cap *
  page198_i59
#ISCELL
  standard offpage *
  page198_i6
#ISCELL
  standard offpage *
  page198_i61
#CELL
  pure_quanta q_cap *
  page198_i65
#CELL
  pure_quanta q_cap *
  page198_i67
#CELL
  pure_quanta q_cap *
  page198_i68
#CELL
  pure_quanta q_cap *
  page198_i69
#ISCELL
  standard offpage *
  page198_i7
#ISCELL
  pure_quanta_power universal_gnd *
  page198_i70
#CELL
  pure_quanta q_cap *
  page198_i71
#ISCELL
  pure_quanta_power vcc_core *
  page198_i72
#ISCELL
  pure_quanta_power universal_gnd *
  page198_i77
#CELL
  pure_quanta q_cap *
  page198_i78
#ISCELL
  pure_quanta_power vcc_core *
  page198_i79
#CELL
  pure_quanta q_cap *
  page198_i8
#CELL
  pure_quanta q_cap *
  page198_i84
#ISCELL
  pure_quanta_power universal_gnd *
  page198_i85
#ISCELL
  pure_quanta_power vcc_core *
  page198_i86
#ISCELL
  pure_quanta_power vcc_core *
  page198_i87
#ISCELL
  standard offpage *
  page198_i89
#CELL
  pure_quanta q_inductor4p_14 *
  page198_i93
#CELL
  pure_quanta q_cap *
  page198_i94
#CELL
  pure_quanta q_res *
  page198_i95
#CELL
  pure_quanta q_cap *
  page198_i97
#CELL
  pure_quanta q_res *
  page198_i98
#CELL
  pure_quanta q_res *
  page198_i99
